FILE_TYPE=LIBRARY_PARTS;
primitive 'PICOPROBE_BXA';
  pin
    '-2':
      PIN_NUMBER='(2)';
      PINUSE='POWER';
      NO_LOAD_CHECK='Both';
      NO_IO_CHECK='Both';
      NO_ASSERT_CHECK='TRUE';
      NO_DIR_CHECK='TRUE';
      ALLOW_CONNECT='TRUE';
    '3_G':
      PIN_NUMBER='(3)';
      PINUSE='POWER';
      NO_LOAD_CHECK='Both';
      NO_IO_CHECK='Both';
      NO_ASSERT_CHECK='TRUE';
      NO_DIR_CHECK='TRUE';
      ALLOW_CONNECT='TRUE';
    '1_P':
      PIN_NUMBER='(1)';
      PINUSE='POWER';
      NO_LOAD_CHECK='Both';
      NO_IO_CHECK='Both';
      NO_ASSERT_CHECK='TRUE';
      NO_DIR_CHECK='TRUE';
      ALLOW_CONNECT='TRUE';
  end_pin;
  body
    PART_NAME='PICOPROBE_BXA';
    BODY_NAME='PICOPROBE_BXA';
    PHYS_DES_PREFIX='J';
    CLASS='IO';
  end_body;
end_primitive;

END.
